# BASEBOARD_FAB2 (Tioga Pass) — schematic netlist excerpt (pin names and nets, part order shuffled) for the footprints in the layout excerpt that follows; sources: Cadence DE-HDL packaged netlist, KiCad conversion of Wiwynn_Tioga_Pass_MB.brd

R1F5  RES  1.00K 1% CHIP  pkg 0402  page 100 : A = PVDDQ_GHJ ; B = M_G_VREF
R1G22  RES  3.16K 1% CHIP  pkg 0402  page 223 : A = VR_PVDDQ_GHJ_XADDR2 ; B = GND
R9E20  RES  0.0 5% CHIP  pkg 0402  page 139 : A = XTAL_25MHZ_IN ; B = XTAL_25MHZ_IN_R

(kicad_pcb
	(version 20260206)
	(generator "pcbnew")
	(generator_version "10.0")
	(general
		(thickness 1.6)
		(legacy_teardrops no)
	)
	(paper "A4")
	(title_block
		(title "Wiwynn_Tioga_Pass_MB.brd")
		(comment 1 "Tioga Pass / footprints 1710-1712 of 4770")
	)
	(layers
		(0 "F.Cu" signal "TOP")
		(4 "In1.Cu" signal "L2GND")
		(6 "In2.Cu" signal "L3")
		(8 "In3.Cu" signal "L4GND")
		(10 "In4.Cu" signal "L5")
		(12 "In5.Cu" signal "L6GND")
		(14 "In6.Cu" signal "L7VCC")
		(16 "In7.Cu" signal "L8VCC")
		(18 "In8.Cu" signal "L9GND")
		(20 "In9.Cu" signal "L10")
		(22 "In10.Cu" signal "L11GND")
		(24 "In11.Cu" signal "L12")
		(26 "In12.Cu" signal "L13GND")
		(2 "B.Cu" signal "BOTTOM")
		(9 "F.Adhes" user "F.Adhesive")
		(11 "B.Adhes" user "B.Adhesive")
		(13 "F.Paste" user "Package Geometry/Pastemask Top")
		(15 "B.Paste" user "Package Geometry/Pastemask Bottom")
		(5 "F.SilkS" user "Ref Des/Silkscreen Top")
		(7 "B.SilkS" user "Ref Des/Silkscreen Bottom")
		(1 "F.Mask" user "Board Geometry/Soldermask Top")
		(3 "B.Mask" user "Board Geometry/Soldermask Bottom")
		(17 "Dwgs.User" user "User.Drawings")
		(19 "Cmts.User" user "User.Comments")
		(21 "Eco1.User" user "User.Eco1")
		(23 "Eco2.User" user "User.Eco2")
		(25 "Edge.Cuts" user "Board Geometry/Outline")
		(27 "Margin" user)
		(31 "F.CrtYd" user "Package Geometry/Place Bound Top")
		(29 "B.CrtYd" user "Package Geometry/Place Bound Bottom")
		(35 "F.Fab" user "Ref Des/Assembly Top")
		(33 "B.Fab" user "Ref Des/Assembly Bottom")
	)
	(footprint ""
		(layer "F.Cu")
		(at 29.028136 -22.994366)
		(property "Reference" "R1F5"
			(at 0 0 0)
			(layer "F.SilkS")
			(hide yes)
			(effects
				(font
					(size 1.27 1.27)
				)
			)
		)
		(property "Value" ""
			(at 0 0 0)
			(layer "F.Fab")
			(effects
				(font
					(size 1.27 1.27)
				)
			)
		)
		(duplicate_pad_numbers_are_jumpers no)
		(fp_poly
			(pts
				(xy -0.2794 -0.1016) (xy 0.2794 -0.1016) (xy 0.2794 0.9906) (xy -0.2794 0.9906)
			)
			(stroke
				(width 0)
				(type default)
			)
			(fill no)
			(layer "F.CrtYd")
		)
		(fp_line
			(start -0.2794 -0.1016)
			(end -0.2794 0.9906)
			(stroke
				(width 0.1)
				(type default)
			)
			(layer "F.Fab")
		)
		(fp_line
			(start -0.2794 0.9906)
			(end 0.2794 0.9906)
			(stroke
				(width 0.1)
				(type default)
			)
			(layer "F.Fab")
		)
		(fp_line
			(start 0.2794 -0.1016)
			(end -0.2794 -0.1016)
			(stroke
				(width 0.1)
				(type default)
			)
			(layer "F.Fab")
		)
		(fp_line
			(start 0.2794 0.9906)
			(end 0.2794 -0.1016)
			(stroke
				(width 0.1)
				(type default)
			)
			(layer "F.Fab")
		)
		(pad "1" smd rect
			(at 0 0)
			(size 0.508 0.508)
			(layers "F.Cu" "F.Mask" "F.Paste")
			(net "PVDDQ_GHJ")
		)
		(pad "2" smd rect
			(at 0 0.889)
			(size 0.508 0.508)
			(layers "F.Cu" "F.Mask" "F.Paste")
			(net "M_G_VREF")
		)
		(zone
			(layer "F.Cu")
			(hatch none 0.5)
			(connect_pads
				(clearance 0)
			)
			(min_thickness 0.25)
			(keepout
				(tracks allowed)
				(vias not_allowed)
				(pads allowed)
				(copperpour not_allowed)
				(footprints allowed)
			)
			(placement
				(enabled no)
				(sheetname "")
			)
			(fill
				(thermal_gap 0.5)
				(thermal_bridge_width 0.5)
				(island_removal_mode 0)
			)
			(polygon
				(pts
					(xy 28.774136 -22.740366) (xy 29.282136 -22.740366) (xy 29.282136 -22.359366) (xy 28.774136 -22.359366)
				)
			)
		)
		(zone
			(layer "F.Cu")
			(hatch none 0.5)
			(connect_pads
				(clearance 0)
			)
			(min_thickness 0.25)
			(keepout
				(tracks not_allowed)
				(vias allowed)
				(pads allowed)
				(copperpour not_allowed)
				(footprints allowed)
			)
			(placement
				(enabled no)
				(sheetname "")
			)
			(fill
				(thermal_gap 0.5)
				(thermal_bridge_width 0.5)
				(island_removal_mode 0)
			)
			(polygon
				(pts
					(xy 28.774136 -22.359366) (xy 29.282136 -22.359366) (xy 29.282136 -22.740366) (xy 28.774136 -22.740366)
				)
			)
		)
	)
	(footprint ""
		(layer "F.Cu")
		(at 8.991346 3.786124 -90)
		(property "Reference" "R1G22"
			(at 0 0 270)
			(layer "F.SilkS")
			(hide yes)
			(effects
				(font
					(size 1.27 1.27)
				)
			)
		)
		(property "Value" ""
			(at 0 0 270)
			(layer "F.Fab")
			(effects
				(font
					(size 1.27 1.27)
				)
			)
		)
		(duplicate_pad_numbers_are_jumpers no)
		(fp_poly
			(pts
				(xy -0.2794 -0.1016) (xy 0.2794 -0.1016) (xy 0.2794 0.9906) (xy -0.2794 0.9906)
			)
			(stroke
				(width 0)
				(type default)
			)
			(fill no)
			(layer "F.CrtYd")
		)
		(fp_line
			(start -0.2794 0.9906)
			(end 0.2794 0.9906)
			(stroke
				(width 0.1)
				(type default)
			)
			(layer "F.Fab")
		)
		(fp_line
			(start 0.2794 0.9906)
			(end 0.2794 -0.1016)
			(stroke
				(width 0.1)
				(type default)
			)
			(layer "F.Fab")
		)
		(fp_line
			(start -0.2794 -0.1016)
			(end -0.2794 0.9906)
			(stroke
				(width 0.1)
				(type default)
			)
			(layer "F.Fab")
		)
		(fp_line
			(start 0.2794 -0.1016)
			(end -0.2794 -0.1016)
			(stroke
				(width 0.1)
				(type default)
			)
			(layer "F.Fab")
		)
		(pad "1" smd rect
			(at 0 0 270)
			(size 0.508 0.508)
			(layers "F.Cu" "F.Mask" "F.Paste")
			(net "VR_PVDDQ_GHJ_XADDR2")
		)
		(pad "2" smd rect
			(at 0 0.889 270)
			(size 0.508 0.508)
			(layers "F.Cu" "F.Mask" "F.Paste")
			(net "GND")
		)
		(zone
			(layer "F.Cu")
			(hatch none 0.5)
			(connect_pads
				(clearance 0)
			)
			(min_thickness 0.25)
			(keepout
				(tracks not_allowed)
				(vias allowed)
				(pads allowed)
				(copperpour not_allowed)
				(footprints allowed)
			)
			(placement
				(enabled no)
				(sheetname "")
			)
			(fill
				(thermal_gap 0.5)
				(thermal_bridge_width 0.5)
				(island_removal_mode 0)
			)
			(polygon
				(pts
					(xy 8.356346 3.532124) (xy 8.356346 4.040124) (xy 8.737346 4.040124) (xy 8.737346 3.532124)
				)
			)
		)
		(zone
			(layer "F.Cu")
			(hatch none 0.5)
			(connect_pads
				(clearance 0)
			)
			(min_thickness 0.25)
			(keepout
				(tracks allowed)
				(vias not_allowed)
				(pads allowed)
				(copperpour not_allowed)
				(footprints allowed)
			)
			(placement
				(enabled no)
				(sheetname "")
			)
			(fill
				(thermal_gap 0.5)
				(thermal_bridge_width 0.5)
				(island_removal_mode 0)
			)
			(polygon
				(pts
					(xy 8.737346 3.532124) (xy 8.737346 4.040124) (xy 8.356346 4.040124) (xy 8.356346 3.532124)
				)
			)
		)
	)
	(footprint ""
		(layer "F.Cu")
		(at 477.3041 -41.3004 90)
		(property "Reference" "R9E20"
			(at 0 0 90)
			(layer "F.SilkS")
			(hide yes)
			(effects
				(font
					(size 1.27 1.27)
				)
			)
		)
		(property "Value" ""
			(at 0 0 90)
			(layer "F.Fab")
			(effects
				(font
					(size 1.27 1.27)
				)
			)
		)
		(duplicate_pad_numbers_are_jumpers no)
		(fp_poly
			(pts
				(xy -0.2794 -0.1016) (xy 0.2794 -0.1016) (xy 0.2794 0.9906) (xy -0.2794 0.9906)
			)
			(stroke
				(width 0)
				(type default)
			)
			(fill no)
			(layer "F.CrtYd")
		)
		(fp_line
			(start 0.2794 -0.1016)
			(end -0.2794 -0.1016)
			(stroke
				(width 0.1)
				(type default)
			)
			(layer "F.Fab")
		)
		(fp_line
			(start -0.2794 -0.1016)
			(end -0.2794 0.9906)
			(stroke
				(width 0.1)
				(type default)
			)
			(layer "F.Fab")
		)
		(fp_line
			(start 0.2794 0.9906)
			(end 0.2794 -0.1016)
			(stroke
				(width 0.1)
				(type default)
			)
			(layer "F.Fab")
		)
		(fp_line
			(start -0.2794 0.9906)
			(end 0.2794 0.9906)
			(stroke
				(width 0.1)
				(type default)
			)
			(layer "F.Fab")
		)
		(pad "1" smd rect
			(at 0 0 90)
			(size 0.508 0.508)
			(layers "F.Cu" "F.Mask" "F.Paste")
			(net "XTAL_25MHZ_IN")
		)
		(pad "2" smd rect
			(at 0 0.889 90)
			(size 0.508 0.508)
			(layers "F.Cu" "F.Mask" "F.Paste")
			(net "XTAL_25MHZ_IN_R")
		)
		(zone
			(layer "F.Cu")
			(hatch none 0.5)
			(connect_pads
				(clearance 0)
			)
			(min_thickness 0.25)
			(keepout
				(tracks allowed)
				(vias not_allowed)
				(pads allowed)
				(copperpour not_allowed)
				(footprints allowed)
			)
			(placement
				(enabled no)
				(sheetname "")
			)
			(fill
				(thermal_gap 0.5)
				(thermal_bridge_width 0.5)
				(island_removal_mode 0)
			)
			(polygon
				(pts
					(xy 477.5581 -41.0464) (xy 477.5581 -41.5544) (xy 477.9391 -41.5544) (xy 477.9391 -41.0464)
				)
			)
		)
		(zone
			(layer "F.Cu")
			(hatch none 0.5)
			(connect_pads
				(clearance 0)
			)
			(min_thickness 0.25)
			(keepout
				(tracks not_allowed)
				(vias allowed)
				(pads allowed)
				(copperpour not_allowed)
				(footprints allowed)
			)
			(placement
				(enabled no)
				(sheetname "")
			)
			(fill
				(thermal_gap 0.5)
				(thermal_bridge_width 0.5)
				(island_removal_mode 0)
			)
			(polygon
				(pts
					(xy 477.9391 -41.0464) (xy 477.9391 -41.5544) (xy 477.5581 -41.5544) (xy 477.5581 -41.0464)
				)
			)
		)
	)
)
